# S9S_MB_2U (Grand Teton) — schematic netlist excerpt (pin names and nets, part order shuffled) for the footprints in the layout excerpt that follows; sources: Cadence DE-HDL packaged netlist, KiCad conversion of 03242023_DA0F0TMBIJ0_F0T_Motherboard_J_brd_V01_OCP.brd

C1794  Q_CAP_DIFFBUS  DIFF BUS_0.22UF 6.3V 20% X6S  pkg C0201  page 175 : \1\ = P5E_CPU0_PE4_TX_C_DN<8> ; \2\ = P5E_CPU0_PE4_TX_DN<8>
ME18  ME_DUMMY_SYMBOL  WEEE EMPTY  pkg WEEE  page 312
PR4243  Q_RES  0 5% CHIP  pkg 0402LF  page 292 : A = NC_PVCCINFAON_CPU1_ACSP4 ; B = GND

(kicad_pcb
	(version 20260206)
	(generator "pcbnew")
	(generator_version "10.0")
	(general
		(thickness 1.6)
		(legacy_teardrops no)
	)
	(paper "A4")
	(title_block
		(title "03242023_DA0F0TMBIJ0_F0T_Motherboard_J_brd_V01_OCP.brd")
		(comment 1 "Grand Teton / footprints 2931-2933 of 6105")
	)
	(layers
		(0 "F.Cu" signal "TOP")
		(4 "In1.Cu" signal "GND")
		(6 "In2.Cu" signal "IN1")
		(8 "In3.Cu" signal "GND1")
		(10 "In4.Cu" signal "IN2")
		(12 "In5.Cu" signal "GND2")
		(14 "In6.Cu" signal "IN3")
		(16 "In7.Cu" signal "GND3")
		(18 "In8.Cu" signal "VCC")
		(20 "In9.Cu" signal "VCC1")
		(22 "In10.Cu" signal "GND4")
		(24 "In11.Cu" signal "IN4")
		(26 "In12.Cu" signal "GND5")
		(28 "In13.Cu" signal "IN5")
		(30 "In14.Cu" signal "GND6")
		(32 "In15.Cu" signal "IN6")
		(34 "In16.Cu" signal "GND7")
		(2 "B.Cu" signal "BOTTOM")
		(9 "F.Adhes" user "F.Adhesive")
		(11 "B.Adhes" user "B.Adhesive")
		(13 "F.Paste" user "Package Geometry/Pastemask Top")
		(15 "B.Paste" user "Package Geometry/Pastemask Bottom")
		(5 "F.SilkS" user "Ref Des/Silkscreen Top")
		(7 "B.SilkS" user "Ref Des/Silkscreen Bottom")
		(1 "F.Mask" user "Board Geometry/Soldermask Top")
		(3 "B.Mask" user "Board Geometry/Soldermask Bottom")
		(17 "Dwgs.User" user "User.Drawings")
		(19 "Cmts.User" user "User.Comments")
		(21 "Eco1.User" user "User.Eco1")
		(23 "Eco2.User" user "User.Eco2")
		(25 "Edge.Cuts" user "Board Geometry/Outline")
		(27 "Margin" user)
		(31 "F.CrtYd" user "Package Geometry/Place Bound Top")
		(29 "B.CrtYd" user "Package Geometry/Place Bound Bottom")
		(35 "F.Fab" user "Ref Des/Assembly Top")
		(33 "B.Fab" user "Ref Des/Assembly Bottom")
	)
	(footprint ""
		(layer "F.Cu")
		(at 31.307278 -138.01979 90)
		(property "Reference" "PR4243"
			(at 0 0 90)
			(layer "F.SilkS")
			(hide yes)
			(effects
				(font
					(size 1.27 1.27)
				)
			)
		)
		(property "Value" ""
			(at 0 0 90)
			(layer "F.Fab")
			(effects
				(font
					(size 1.27 1.27)
				)
			)
		)
		(duplicate_pad_numbers_are_jumpers no)
		(fp_line
			(start 0.7874 -0.4064)
			(end 0.7874 0.4064)
			(stroke
				(width 0.1524)
				(type default)
			)
			(layer "F.SilkS")
		)
		(fp_line
			(start -0.7874 -0.4064)
			(end 0.7874 -0.4064)
			(stroke
				(width 0.1524)
				(type default)
			)
			(layer "F.SilkS")
		)
		(fp_line
			(start 0.7874 0.4064)
			(end -0.7874 0.4064)
			(stroke
				(width 0.1524)
				(type default)
			)
			(layer "F.SilkS")
		)
		(fp_line
			(start -0.7874 0.4064)
			(end -0.7874 -0.4064)
			(stroke
				(width 0.1524)
				(type default)
			)
			(layer "F.SilkS")
		)
		(fp_line
			(start -0.12065 -0.305054)
			(end -0.12065 -0.2794)
			(stroke
				(width 0.1)
				(type default)
			)
			(layer "F.Fab")
		)
		(fp_line
			(start -0.67945 -0.305054)
			(end -0.12065 -0.305054)
			(stroke
				(width 0.1)
				(type default)
			)
			(layer "F.Fab")
		)
		(fp_line
			(start 0.67945 -0.3048)
			(end 0.67945 0.3048)
			(stroke
				(width 0.1)
				(type default)
			)
			(layer "F.Fab")
		)
		(fp_line
			(start 0.12065 -0.3048)
			(end 0.67945 -0.3048)
			(stroke
				(width 0.1)
				(type default)
			)
			(layer "F.Fab")
		)
		(fp_line
			(start 0.12065 -0.2794)
			(end 0.12065 -0.3048)
			(stroke
				(width 0.1)
				(type default)
			)
			(layer "F.Fab")
		)
		(fp_line
			(start -0.12065 -0.2794)
			(end 0.12065 -0.2794)
			(stroke
				(width 0.1)
				(type default)
			)
			(layer "F.Fab")
		)
		(fp_line
			(start 0.120396 0.2794)
			(end -0.12065 0.2794)
			(stroke
				(width 0.1)
				(type default)
			)
			(layer "F.Fab")
		)
		(fp_line
			(start -0.12065 0.2794)
			(end -0.12065 0.3048)
			(stroke
				(width 0.1)
				(type default)
			)
			(layer "F.Fab")
		)
		(fp_line
			(start 0.67945 0.3048)
			(end 0.120396 0.3048)
			(stroke
				(width 0.1)
				(type default)
			)
			(layer "F.Fab")
		)
		(fp_line
			(start 0.120396 0.3048)
			(end 0.120396 0.2794)
			(stroke
				(width 0.1)
				(type default)
			)
			(layer "F.Fab")
		)
		(fp_line
			(start -0.12065 0.3048)
			(end -0.67945 0.3048)
			(stroke
				(width 0.1)
				(type default)
			)
			(layer "F.Fab")
		)
		(fp_line
			(start -0.67945 0.3048)
			(end -0.67945 -0.305054)
			(stroke
				(width 0.1)
				(type default)
			)
			(layer "F.Fab")
		)
		(pad "1" smd circle
			(at -0.40005 0 90)
			(size 0 0)
			(layers "F.Cu" "F.Mask" "F.Paste")
			(net "NC_PVCCINFAON_CPU1_ACSP4")
		)
		(pad "2" smd circle
			(at 0.40005 0 90)
			(size 0 0)
			(layers "F.Cu" "F.Mask" "F.Paste")
			(net "GND")
		)
	)
	(footprint ""
		(layer "F.Cu")
		(at 344.764106 -389.052816)
		(property "Reference" "ME18"
			(at 0 0 0)
			(layer "F.SilkS")
			(hide yes)
			(effects
				(font
					(size 1.27 1.27)
				)
			)
		)
		(property "Value" ""
			(at 0 0 0)
			(layer "F.Fab")
			(effects
				(font
					(size 1.27 1.27)
				)
			)
		)
		(duplicate_pad_numbers_are_jumpers no)
		(fp_rect
			(start 0 0)
			(end 3.3401 -0.5842)
			(stroke
				(width 0)
				(type default)
			)
			(fill yes)
			(layer "F.SilkS")
		)
		(fp_rect
			(start 1.32715 -3.2512)
			(end 2.01295 -3.4417)
			(stroke
				(width 0)
				(type default)
			)
			(fill yes)
			(layer "F.SilkS")
		)
		(fp_poly
			(pts
				(xy 0.92075 -1.1557) (xy 0.888492 -1.51384) (xy 0.094488 -0.693928) (xy -0.070612 -0.681228) (xy -0.197612 -0.820928)
				(xy 0.852678 -1.91262) (xy 0.728472 -3.29184) (xy -0.248412 -4.300728) (xy -0.184912 -4.478528)
				(xy -0.007112 -4.503928) (xy 0.684022 -3.785616) (xy 0.65659 -4.0894) (xy 0.97155 -4.3434) (xy 1.22555 -4.3561)
				(xy 1.46685 -4.4704) (xy 2.01295 -4.4704) (xy 2.15265 -4.4069) (xy 2.44475 -4.191) (xy 2.49555 -4.191)
				(xy 2.59715 -4.2926) (xy 2.80035 -4.2672) (xy 2.88925 -4.1656) (xy 2.88925 -4.029456) (xy 3.345688 -4.503928)
				(xy 3.523488 -4.478528) (xy 3.586988 -4.300728) (xy 2.88925 -3.58013) (xy 2.88925 -3.3147) (xy 2.82575 -3.2385)
				(xy 2.67335 -3.2385) (xy 2.521966 -1.875282) (xy 2.545842 -1.85039)
				(arc
					(start 2.55905 -1.8415)
					(mid 2.648099 -1.766068)
					(end 2.717292 -1.672082)
				)
				(xy 3.536188 -0.820928) (xy 3.409188 -0.681228) (xy 3.244088 -0.693928)
				(arc
					(start 2.737612 -1.216914)
					(mid 2.31728 -0.925553)
					(end 1.86055 -1.1557)
				)
			)
			(stroke
				(width 0)
				(type default)
			)
			(fill yes)
			(layer "F.SilkS")
		)
	)
	(footprint ""
		(layer "F.Cu")
		(at 328.460608 -402.371052 -90)
		(property "Reference" "C1794"
			(at 0 0 270)
			(layer "F.SilkS")
			(hide yes)
			(effects
				(font
					(size 1.27 1.27)
				)
			)
		)
		(property "Value" ""
			(at 0 0 270)
			(layer "F.Fab")
			(effects
				(font
					(size 1.27 1.27)
				)
			)
		)
		(duplicate_pad_numbers_are_jumpers no)
		(fp_line
			(start -0.299974 0.150114)
			(end -0.299974 -0.150114)
			(stroke
				(width 0.1)
				(type default)
			)
			(layer "F.Fab")
		)
		(fp_line
			(start 0.299974 0.150114)
			(end -0.299974 0.150114)
			(stroke
				(width 0.1)
				(type default)
			)
			(layer "F.Fab")
		)
		(fp_line
			(start -0.299974 -0.150114)
			(end 0.299974 -0.150114)
			(stroke
				(width 0.1)
				(type default)
			)
			(layer "F.Fab")
		)
		(fp_line
			(start 0.299974 -0.150114)
			(end 0.299974 0.150114)
			(stroke
				(width 0.1)
				(type default)
			)
			(layer "F.Fab")
		)
		(pad "1" smd rect
			(at -0.2667 0 270)
			(size 0.3048 0.381)
			(layers "F.Cu" "F.Mask" "F.Paste")
			(net "P5E_CPU0_PE4_TX_C_DN<8>")
		)
		(pad "2" smd rect
			(at 0.2667 0 270)
			(size 0.3048 0.381)
			(layers "F.Cu" "F.Mask" "F.Paste")
			(net "P5E_CPU0_PE4_TX_DN<8>")
		)
	)
)
